(kicad_pcb
	(version 20260206)
	(generator "pcbnew")
	(generator_version "10.0")
	(general
		(thickness 1.6)
		(legacy_teardrops no)
	)
	(paper "A4")
	(title_block
		(title "Wiwynn_Tioga_Pass_MB.brd")
		(comment 1 "Tioga Pass / footprints 3159-3166 of 4770")
	)
	(layers
		(0 "F.Cu" signal "TOP")
		(4 "In1.Cu" signal "L2GND")
		(6 "In2.Cu" signal "L3")
		(8 "In3.Cu" signal "L4GND")
		(10 "In4.Cu" signal "L5")
		(12 "In5.Cu" signal "L6GND")
		(14 "In6.Cu" signal "L7VCC")
		(16 "In7.Cu" signal "L8VCC")
		(18 "In8.Cu" signal "L9GND")
		(20 "In9.Cu" signal "L10")
		(22 "In10.Cu" signal "L11GND")
		(24 "In11.Cu" signal "L12")
		(26 "In12.Cu" signal "L13GND")
		(2 "B.Cu" signal "BOTTOM")
		(9 "F.Adhes" user "F.Adhesive")
		(11 "B.Adhes" user "B.Adhesive")
		(13 "F.Paste" user "Package Geometry/Pastemask Top")
		(15 "B.Paste" user "Package Geometry/Pastemask Bottom")
		(5 "F.SilkS" user "Ref Des/Silkscreen Top")
		(7 "B.SilkS" user "Ref Des/Silkscreen Bottom")
		(1 "F.Mask" user "Board Geometry/Soldermask Top")
		(3 "B.Mask" user "Board Geometry/Soldermask Bottom")
		(17 "Dwgs.User" user "User.Drawings")
		(19 "Cmts.User" user "User.Comments")
		(21 "Eco1.User" user "User.Eco1")
		(23 "Eco2.User" user "User.Eco2")
		(25 "Edge.Cuts" user "Board Geometry/Outline")
		(27 "Margin" user)
		(31 "F.CrtYd" user "Package Geometry/Place Bound Top")
		(29 "B.CrtYd" user "Package Geometry/Place Bound Bottom")
		(35 "F.Fab" user "Ref Des/Assembly Top")
		(33 "B.Fab" user "Ref Des/Assembly Bottom")
	)
	(footprint ""
		(layer "B.Cu")
		(at 488.98429 -29.3116)
		(property "Reference" "R1R9"
			(at 0.8382 -0.67818 0)
			(unlocked yes)
			(layer "B.SilkS")
			(effects
				(font
					(size 0.4064 0.254)
					(thickness 0.1524)
				)
				(justify left mirror)
			)
		)
		(property "Value" ""
			(at 0 0 0)
			(layer "B.Fab")
			(effects
				(font
					(size 1.27 1.27)
				)
				(justify mirror)
			)
		)
		(duplicate_pad_numbers_are_jumpers no)
		(fp_poly
			(pts
				(xy 0.2794 -0.1016) (xy -0.2794 -0.1016) (xy -0.2794 0.9906) (xy 0.2794 0.9906)
			)
			(stroke
				(width 0)
				(type default)
			)
			(fill no)
			(layer "B.CrtYd")
		)
		(fp_line
			(start -0.2794 -0.1016)
			(end 0.2794 -0.1016)
			(stroke
				(width 0.1)
				(type default)
			)
			(layer "B.Fab")
		)
		(fp_line
			(start -0.2794 0.9906)
			(end -0.2794 -0.1016)
			(stroke
				(width 0.1)
				(type default)
			)
			(layer "B.Fab")
		)
		(fp_line
			(start 0.2794 -0.1016)
			(end 0.2794 0.9906)
			(stroke
				(width 0.1)
				(type default)
			)
			(layer "B.Fab")
		)
		(fp_line
			(start 0.2794 0.9906)
			(end -0.2794 0.9906)
			(stroke
				(width 0.1)
				(type default)
			)
			(layer "B.Fab")
		)
		(pad "1" smd rect
			(at 0 0 180)
			(size 0.508 0.508)
			(layers "B.Cu" "B.Mask" "B.Paste")
			(net "P3V3_STBY")
		)
		(pad "2" smd rect
			(at 0 0.889 180)
			(size 0.508 0.508)
			(layers "B.Cu" "B.Mask" "B.Paste")
			(net "PU_NV_HOLD_N")
		)
		(zone
			(layer "B.Cu")
			(hatch none 0.5)
			(connect_pads
				(clearance 0)
			)
			(min_thickness 0.25)
			(keepout
				(tracks allowed)
				(vias not_allowed)
				(pads allowed)
				(copperpour not_allowed)
				(footprints allowed)
			)
			(placement
				(enabled no)
				(sheetname "")
			)
			(fill
				(thermal_gap 0.5)
				(thermal_bridge_width 0.5)
				(island_removal_mode 0)
			)
			(polygon
				(pts
					(xy 489.23829 -29.0576) (xy 488.73029 -29.0576) (xy 488.73029 -28.6766) (xy 489.23829 -28.6766)
				)
			)
		)
		(zone
			(layer "B.Cu")
			(hatch none 0.5)
			(connect_pads
				(clearance 0)
			)
			(min_thickness 0.25)
			(keepout
				(tracks not_allowed)
				(vias allowed)
				(pads allowed)
				(copperpour not_allowed)
				(footprints allowed)
			)
			(placement
				(enabled no)
				(sheetname "")
			)
			(fill
				(thermal_gap 0.5)
				(thermal_bridge_width 0.5)
				(island_removal_mode 0)
			)
			(polygon
				(pts
					(xy 489.23829 -28.6766) (xy 488.73029 -28.6766) (xy 488.73029 -29.0576) (xy 489.23829 -29.0576)
				)
			)
		)
	)
	(footprint ""
		(layer "B.Cu")
		(at 245.7577 -8.1534 -90)
		(property "Reference" "C5U9"
			(at -1.848866 0.752348 270)
			(unlocked yes)
			(layer "B.SilkS")
			(effects
				(font
					(size 1.27 0.9652)
					(thickness 0.1524)
				)
				(justify mirror)
			)
		)
		(property "Value" ""
			(at 0 0 90)
			(layer "B.Fab")
			(effects
				(font
					(size 1.27 1.27)
				)
				(justify mirror)
			)
		)
		(duplicate_pad_numbers_are_jumpers no)
		(fp_rect
			(start 0.500126 1.598422)
			(end -0.500126 -0.201422)
			(stroke
				(width 0)
				(type default)
			)
			(fill no)
			(layer "B.CrtYd")
		)
		(fp_line
			(start -0.500126 1.598422)
			(end 0.500126 1.598422)
			(stroke
				(width 0.1)
				(type default)
			)
			(layer "B.Fab")
		)
		(fp_line
			(start 0.500126 1.598422)
			(end 0.500126 -0.201422)
			(stroke
				(width 0.1)
				(type default)
			)
			(layer "B.Fab")
		)
		(fp_line
			(start -0.500126 -0.201422)
			(end -0.500126 1.598422)
			(stroke
				(width 0.1)
				(type default)
			)
			(layer "B.Fab")
		)
		(fp_line
			(start 0.500126 -0.201422)
			(end -0.500126 -0.201422)
			(stroke
				(width 0.1)
				(type default)
			)
			(layer "B.Fab")
		)
		(pad "1" smd rect
			(at 0 0 180)
			(size 0.889 0.9906)
			(layers "B.Cu" "B.Mask" "B.Paste")
			(net "PVDDQ_ABC")
		)
		(pad "2" smd rect
			(at 0 1.397 180)
			(size 0.889 0.9906)
			(layers "B.Cu" "B.Mask" "B.Paste")
			(net "GND")
		)
		(zone
			(layer "B.Cu")
			(hatch none 0.5)
			(connect_pads
				(clearance 0)
			)
			(min_thickness 0.25)
			(keepout
				(tracks not_allowed)
				(vias allowed)
				(pads allowed)
				(copperpour not_allowed)
				(footprints allowed)
			)
			(placement
				(enabled no)
				(sheetname "")
			)
			(fill
				(thermal_gap 0.5)
				(thermal_bridge_width 0.5)
				(island_removal_mode 0)
			)
			(polygon
				(pts
					(xy 244.8052 -7.6581) (xy 245.3132 -7.6581) (xy 245.3132 -8.6487) (xy 244.8052 -8.6487)
				)
			)
		)
		(zone
			(layer "B.Cu")
			(hatch none 0.5)
			(connect_pads
				(clearance 0)
			)
			(min_thickness 0.25)
			(keepout
				(tracks allowed)
				(vias not_allowed)
				(pads allowed)
				(copperpour not_allowed)
				(footprints allowed)
			)
			(placement
				(enabled no)
				(sheetname "")
			)
			(fill
				(thermal_gap 0.5)
				(thermal_bridge_width 0.5)
				(island_removal_mode 0)
			)
			(polygon
				(pts
					(xy 244.8052 -7.6581) (xy 245.3132 -7.6581) (xy 245.3132 -8.6487) (xy 244.8052 -8.6487)
				)
			)
		)
	)
	(footprint ""
		(layer "B.Cu")
		(at 11.881358 3.20802)
		(property "Reference" "R12W11"
			(at 0 0 0)
			(layer "B.SilkS")
			(hide yes)
			(effects
				(font
					(size 1.27 1.27)
				)
				(justify mirror)
			)
		)
		(property "Value" "*"
			(at 0 -8.9535 0)
			(unlocked yes)
			(layer "B.Fab")
			(hide yes)
			(effects
				(font
					(size 1.27 1.016)
					(thickness 0.1524)
				)
				(justify mirror)
			)
		)
		(property "Device Type" "665KR5B-1-GP_SMD-RG3-665KR5B-1A"
			(at 0 -10.6299 0)
			(unlocked yes)
			(layer "B.Fab")
			(hide yes)
			(effects
				(font
					(size 1.27 1.016)
					(thickness 0.1524)
				)
				(justify mirror)
			)
		)
		(duplicate_pad_numbers_are_jumpers no)
		(fp_line
			(start -0.889 -1.7018)
			(end -0.889 -0.381)
			(stroke
				(width 0.1524)
				(type default)
			)
			(layer "B.SilkS")
		)
		(fp_line
			(start -0.889 -1.7018)
			(end 0.889 -1.7018)
			(stroke
				(width 0.1524)
				(type default)
			)
			(layer "B.SilkS")
		)
		(fp_line
			(start -0.889 1.7018)
			(end -0.889 -0.508)
			(stroke
				(width 0.1524)
				(type default)
			)
			(layer "B.SilkS")
		)
		(fp_line
			(start 0.889 -1.7018)
			(end 0.889 0.2794)
			(stroke
				(width 0.1524)
				(type default)
			)
			(layer "B.SilkS")
		)
		(fp_line
			(start 0.889 0.0762)
			(end 0.889 1.7018)
			(stroke
				(width 0.1524)
				(type default)
			)
			(layer "B.SilkS")
		)
		(fp_line
			(start 0.889 1.7018)
			(end -0.889 1.7018)
			(stroke
				(width 0.1524)
				(type default)
			)
			(layer "B.SilkS")
		)
		(fp_poly
			(pts
				(xy -0.9652 -1.778) (xy -0.9652 1.778) (xy 0.9652 1.778) (xy 0.9652 -1.778)
			)
			(stroke
				(width 0)
				(type default)
			)
			(fill no)
			(layer "B.CrtYd")
		)
		(fp_rect
			(start 0.9652 1.778)
			(end -0.9652 -1.778)
			(stroke
				(width 0)
				(type default)
			)
			(fill no)
			(layer "B.Fab")
		)
		(pad "1" smd rect
			(at 0 -0.9652 180)
			(size 1.397 1.143)
			(layers "B.Cu" "B.Mask" "B.Paste")
			(net "P12V_STBY")
		)
		(pad "2" smd rect
			(at 0 0.9652 180)
			(size 1.397 1.143)
			(layers "B.Cu" "B.Mask" "B.Paste")
			(net "VR_PVDDQ_GHJ_AIINSEN")
		)
	)
	(footprint ""
		(layer "B.Cu")
		(at 390.144 -87.4395)
		(property "Reference" "R2N22"
			(at 0.8382 -0.67818 0)
			(unlocked yes)
			(layer "B.SilkS")
			(effects
				(font
					(size 0.4064 0.254)
					(thickness 0.1524)
				)
				(justify left mirror)
			)
		)
		(property "Value" ""
			(at 0 0 0)
			(layer "B.Fab")
			(effects
				(font
					(size 1.27 1.27)
				)
				(justify mirror)
			)
		)
		(duplicate_pad_numbers_are_jumpers no)
		(fp_poly
			(pts
				(xy 0.2794 -0.1016) (xy -0.2794 -0.1016) (xy -0.2794 0.9906) (xy 0.2794 0.9906)
			)
			(stroke
				(width 0)
				(type default)
			)
			(fill no)
			(layer "B.CrtYd")
		)
		(fp_line
			(start -0.2794 -0.1016)
			(end 0.2794 -0.1016)
			(stroke
				(width 0.1)
				(type default)
			)
			(layer "B.Fab")
		)
		(fp_line
			(start -0.2794 0.9906)
			(end -0.2794 -0.1016)
			(stroke
				(width 0.1)
				(type default)
			)
			(layer "B.Fab")
		)
		(fp_line
			(start 0.2794 -0.1016)
			(end 0.2794 0.9906)
			(stroke
				(width 0.1)
				(type default)
			)
			(layer "B.Fab")
		)
		(fp_line
			(start 0.2794 0.9906)
			(end -0.2794 0.9906)
			(stroke
				(width 0.1)
				(type default)
			)
			(layer "B.Fab")
		)
		(pad "1" smd rect
			(at 0 0 180)
			(size 0.508 0.508)
			(layers "B.Cu" "B.Mask" "B.Paste")
			(net "SGPIO_PCH_SSATA_CLOCK")
		)
		(pad "2" smd rect
			(at 0 0.889 180)
			(size 0.508 0.508)
			(layers "B.Cu" "B.Mask" "B.Paste")
			(net "SGPIO_PCH_SSATA_CLOCK_R")
		)
		(zone
			(layer "B.Cu")
			(hatch none 0.5)
			(connect_pads
				(clearance 0)
			)
			(min_thickness 0.25)
			(keepout
				(tracks allowed)
				(vias not_allowed)
				(pads allowed)
				(copperpour not_allowed)
				(footprints allowed)
			)
			(placement
				(enabled no)
				(sheetname "")
			)
			(fill
				(thermal_gap 0.5)
				(thermal_bridge_width 0.5)
				(island_removal_mode 0)
			)
			(polygon
				(pts
					(xy 390.398 -87.1855) (xy 389.89 -87.1855) (xy 389.89 -86.8045) (xy 390.398 -86.8045)
				)
			)
		)
		(zone
			(layer "B.Cu")
			(hatch none 0.5)
			(connect_pads
				(clearance 0)
			)
			(min_thickness 0.25)
			(keepout
				(tracks not_allowed)
				(vias allowed)
				(pads allowed)
				(copperpour not_allowed)
				(footprints allowed)
			)
			(placement
				(enabled no)
				(sheetname "")
			)
			(fill
				(thermal_gap 0.5)
				(thermal_bridge_width 0.5)
				(island_removal_mode 0)
			)
			(polygon
				(pts
					(xy 390.398 -86.8045) (xy 389.89 -86.8045) (xy 389.89 -87.1855) (xy 390.398 -87.1855)
				)
			)
		)
	)
	(footprint ""
		(layer "B.Cu")
		(at 93.101668 -3.321812 -90)
		(property "Reference" "C5G84"
			(at -1.14681 0.76708 0)
			(unlocked yes)
			(layer "B.SilkS")
			(effects
				(font
					(size 0.7874 0.5842)
					(thickness 0.1524)
				)
				(justify mirror)
			)
		)
		(property "Value" ""
			(at 0 0 90)
			(layer "B.Fab")
			(effects
				(font
					(size 1.27 1.27)
				)
				(justify mirror)
			)
		)
		(duplicate_pad_numbers_are_jumpers no)
		(fp_rect
			(start 0.4953 1.6002)
			(end -0.4953 -0.2032)
			(stroke
				(width 0)
				(type default)
			)
			(fill no)
			(layer "B.CrtYd")
		)
		(fp_line
			(start -0.4953 1.6002)
			(end 0.4953 1.6002)
			(stroke
				(width 0.1)
				(type default)
			)
			(layer "B.Fab")
		)
		(fp_line
			(start 0.4953 1.6002)
			(end 0.4953 -0.2032)
			(stroke
				(width 0.1)
				(type default)
			)
			(layer "B.Fab")
		)
		(fp_line
			(start -0.4953 -0.2032)
			(end -0.4953 1.6002)
			(stroke
				(width 0.1)
				(type default)
			)
			(layer "B.Fab")
		)
		(fp_line
			(start 0.4953 -0.2032)
			(end -0.4953 -0.2032)
			(stroke
				(width 0.1)
				(type default)
			)
			(layer "B.Fab")
		)
		(pad "1" smd rect
			(at 0 0 90)
			(size 0.762 0.889)
			(layers "B.Cu" "B.Mask" "B.Paste")
			(net "PVDDQ_GHJ")
		)
		(pad "2" smd rect
			(at 0 1.397 90)
			(size 0.762 0.889)
			(layers "B.Cu" "B.Mask" "B.Paste")
			(net "GND")
		)
		(zone
			(layer "B.Cu")
			(hatch none 0.5)
			(connect_pads
				(clearance 0)
			)
			(min_thickness 0.25)
			(keepout
				(tracks not_allowed)
				(vias allowed)
				(pads allowed)
				(copperpour not_allowed)
				(footprints allowed)
			)
			(placement
				(enabled no)
				(sheetname "")
			)
			(fill
				(thermal_gap 0.5)
				(thermal_bridge_width 0.5)
				(island_removal_mode 0)
			)
			(polygon
				(pts
					(xy 92.149168 -2.940812) (xy 92.657168 -2.940812) (xy 92.657168 -3.702812) (xy 92.149168 -3.702812)
				)
			)
		)
	)
	(footprint ""
		(layer "B.Cu")
		(at 270.637 3.81 90)
		(property "Reference" "C5U14"
			(at 0 0 90)
			(layer "B.SilkS")
			(hide yes)
			(effects
				(font
					(size 1.27 1.27)
				)
				(justify mirror)
			)
		)
		(property "Value" ""
			(at 0 0 90)
			(layer "B.Fab")
			(effects
				(font
					(size 1.27 1.27)
				)
				(justify mirror)
			)
		)
		(duplicate_pad_numbers_are_jumpers no)
		(fp_rect
			(start -0.7239 -0.2159)
			(end 0.7239 1.9939)
			(stroke
				(width 0)
				(type default)
			)
			(fill no)
			(layer "B.CrtYd")
		)
		(fp_line
			(start 0.7239 -0.2159)
			(end 0.7239 1.9939)
			(stroke
				(width 0.1)
				(type default)
			)
			(layer "B.Fab")
		)
		(fp_line
			(start -0.7239 -0.2159)
			(end 0.7239 -0.2159)
			(stroke
				(width 0.1)
				(type default)
			)
			(layer "B.Fab")
		)
		(fp_line
			(start 0.7239 1.9939)
			(end -0.7239 1.9939)
			(stroke
				(width 0.1)
				(type default)
			)
			(layer "B.Fab")
		)
		(fp_line
			(start -0.7239 1.9939)
			(end -0.7239 -0.2159)
			(stroke
				(width 0.1)
				(type default)
			)
			(layer "B.Fab")
		)
		(pad "1" smd rect
			(at 0 0 270)
			(size 1.27 1.016)
			(layers "B.Cu" "B.Mask" "B.Paste")
			(net "PVDDQ_ABC")
		)
		(pad "2" smd rect
			(at 0 1.778 270)
			(size 1.27 1.016)
			(layers "B.Cu" "B.Mask" "B.Paste")
			(net "GND")
		)
		(zone
			(layer "B.Cu")
			(hatch none 0.5)
			(connect_pads
				(clearance 0)
			)
			(min_thickness 0.25)
			(keepout
				(tracks not_allowed)
				(vias allowed)
				(pads allowed)
				(copperpour not_allowed)
				(footprints allowed)
			)
			(placement
				(enabled no)
				(sheetname "")
			)
			(fill
				(thermal_gap 0.5)
				(thermal_bridge_width 0.5)
				(island_removal_mode 0)
			)
			(polygon
				(pts
					(xy 271.145 4.445) (xy 271.907 4.445) (xy 271.907 3.175) (xy 271.145 3.175)
				)
			)
		)
	)
	(footprint ""
		(layer "B.Cu")
		(at 405.257 -116.7765 180)
		(property "Reference" "C2M12"
			(at 0 0 0)
			(layer "B.SilkS")
			(hide yes)
			(effects
				(font
					(size 1.27 1.27)
				)
				(justify mirror)
			)
		)
		(property "Value" ""
			(at 0 0 0)
			(layer "B.Fab")
			(effects
				(font
					(size 1.27 1.27)
				)
				(justify mirror)
			)
		)
		(duplicate_pad_numbers_are_jumpers no)
		(fp_poly
			(pts
				(xy 0.4953 -0.2032) (xy -0.4953 -0.2032) (xy -0.4953 1.6002) (xy 0.4953 1.6002)
			)
			(stroke
				(width 0)
				(type default)
			)
			(fill no)
			(layer "B.CrtYd")
		)
		(fp_line
			(start 0.4953 1.6002)
			(end 0.4953 -0.2032)
			(stroke
				(width 0.1)
				(type default)
			)
			(layer "B.Fab")
		)
		(fp_line
			(start 0.4953 -0.2032)
			(end -0.4953 -0.2032)
			(stroke
				(width 0.1)
				(type default)
			)
			(layer "B.Fab")
		)
		(fp_line
			(start -0.4953 1.6002)
			(end 0.4953 1.6002)
			(stroke
				(width 0.1)
				(type default)
			)
			(layer "B.Fab")
		)
		(fp_line
			(start -0.4953 -0.2032)
			(end -0.4953 1.6002)
			(stroke
				(width 0.1)
				(type default)
			)
			(layer "B.Fab")
		)
		(pad "1" smd rect
			(at 0 0)
			(size 0.762 0.889)
			(layers "B.Cu" "B.Mask" "B.Paste")
			(net "P1V05_PCH_STBY")
		)
		(pad "2" smd rect
			(at 0 1.397)
			(size 0.762 0.889)
			(layers "B.Cu" "B.Mask" "B.Paste")
			(net "GND")
		)
		(zone
			(layer "B.Cu")
			(hatch none 0.5)
			(connect_pads
				(clearance 0)
			)
			(min_thickness 0.25)
			(keepout
				(tracks not_allowed)
				(vias allowed)
				(pads allowed)
				(copperpour not_allowed)
				(footprints allowed)
			)
			(placement
				(enabled no)
				(sheetname "")
			)
			(fill
				(thermal_gap 0.5)
				(thermal_bridge_width 0.5)
				(island_removal_mode 0)
			)
			(polygon
				(pts
					(xy 404.876 -117.221) (xy 405.638 -117.221) (xy 405.638 -117.729) (xy 404.876 -117.729)
				)
			)
		)
	)
	(footprint ""
		(layer "B.Cu")
		(at 17.526 -87.7062)
		(property "Reference" "R9P2"
			(at 0 0 0)
			(layer "B.SilkS")
			(hide yes)
			(effects
				(font
					(size 1.27 1.27)
				)
				(justify mirror)
			)
		)
		(property "Value" ""
			(at 0 0 0)
			(layer "B.Fab")
			(effects
				(font
					(size 1.27 1.27)
				)
				(justify mirror)
			)
		)
		(duplicate_pad_numbers_are_jumpers no)
		(fp_poly
			(pts
				(xy 0.2794 -0.1016) (xy -0.2794 -0.1016) (xy -0.2794 0.9906) (xy 0.2794 0.9906)
			)
			(stroke
				(width 0)
				(type default)
			)
			(fill no)
			(layer "B.CrtYd")
		)
		(fp_line
			(start -0.2794 -0.1016)
			(end 0.2794 -0.1016)
			(stroke
				(width 0.1)
				(type default)
			)
			(layer "B.Fab")
		)
		(fp_line
			(start -0.2794 0.9906)
			(end -0.2794 -0.1016)
			(stroke
				(width 0.1)
				(type default)
			)
			(layer "B.Fab")
		)
		(fp_line
			(start 0.2794 -0.1016)
			(end 0.2794 0.9906)
			(stroke
				(width 0.1)
				(type default)
			)
			(layer "B.Fab")
		)
		(fp_line
			(start 0.2794 0.9906)
			(end -0.2794 0.9906)
			(stroke
				(width 0.1)
				(type default)
			)
			(layer "B.Fab")
		)
		(pad "1" smd rect
			(at 0 0 180)
			(size 0.508 0.508)
			(layers "B.Cu" "B.Mask" "B.Paste")
			(net "PVCCIO_CPU1")
		)
		(pad "2" smd rect
			(at 0 0.889 180)
			(size 0.508 0.508)
			(layers "B.Cu" "B.Mask" "B.Paste")
			(net "SVID_CLK0_CPU1_R")
		)
		(zone
			(layer "B.Cu")
			(hatch none 0.5)
			(connect_pads
				(clearance 0)
			)
			(min_thickness 0.25)
			(keepout
				(tracks allowed)
				(vias not_allowed)
				(pads allowed)
				(copperpour not_allowed)
				(footprints allowed)
			)
			(placement
				(enabled no)
				(sheetname "")
			)
			(fill
				(thermal_gap 0.5)
				(thermal_bridge_width 0.5)
				(island_removal_mode 0)
			)
			(polygon
				(pts
					(xy 17.78 -87.4522) (xy 17.272 -87.4522) (xy 17.272 -87.0712) (xy 17.78 -87.0712)
				)
			)
		)
		(zone
			(layer "B.Cu")
			(hatch none 0.5)
			(connect_pads
				(clearance 0)
			)
			(min_thickness 0.25)
			(keepout
				(tracks not_allowed)
				(vias allowed)
				(pads allowed)
				(copperpour not_allowed)
				(footprints allowed)
			)
			(placement
				(enabled no)
				(sheetname "")
			)
			(fill
				(thermal_gap 0.5)
				(thermal_bridge_width 0.5)
				(island_removal_mode 0)
			)
			(polygon
				(pts
					(xy 17.78 -87.0712) (xy 17.272 -87.0712) (xy 17.272 -87.4522) (xy 17.78 -87.4522)
				)
			)
		)
	)
)
